(kicad_pcb
	(version 20260206)
	(generator "pcbnew")
	(generator_version "10.0")
	(general
		(thickness 1.6)
		(legacy_teardrops no)
	)
	(paper "A4")
	(title_block
		(title "03242023_DA0F0TMBIJ0_F0T_Motherboard_J_brd_V01_OCP.brd")
		(comment 1 "Grand Teton / footprint 1585 of 6105 (U4), pads 340-449 of 749")
	)
	(layers
		(0 "F.Cu" signal "TOP")
		(4 "In1.Cu" signal "GND")
		(6 "In2.Cu" signal "IN1")
		(8 "In3.Cu" signal "GND1")
		(10 "In4.Cu" signal "IN2")
		(12 "In5.Cu" signal "GND2")
		(14 "In6.Cu" signal "IN3")
		(16 "In7.Cu" signal "GND3")
		(18 "In8.Cu" signal "VCC")
		(20 "In9.Cu" signal "VCC1")
		(22 "In10.Cu" signal "GND4")
		(24 "In11.Cu" signal "IN4")
		(26 "In12.Cu" signal "GND5")
		(28 "In13.Cu" signal "IN5")
		(30 "In14.Cu" signal "GND6")
		(32 "In15.Cu" signal "IN6")
		(34 "In16.Cu" signal "GND7")
		(2 "B.Cu" signal "BOTTOM")
		(9 "F.Adhes" user "F.Adhesive")
		(11 "B.Adhes" user "B.Adhesive")
		(13 "F.Paste" user "Package Geometry/Pastemask Top")
		(15 "B.Paste" user "Package Geometry/Pastemask Bottom")
		(5 "F.SilkS" user "Ref Des/Silkscreen Top")
		(7 "B.SilkS" user "Ref Des/Silkscreen Bottom")
		(1 "F.Mask" user "Board Geometry/Soldermask Top")
		(3 "B.Mask" user "Board Geometry/Soldermask Bottom")
		(17 "Dwgs.User" user "User.Drawings")
		(19 "Cmts.User" user "User.Comments")
		(21 "Eco1.User" user "User.Eco1")
		(23 "Eco2.User" user "User.Eco2")
		(25 "Edge.Cuts" user "Board Geometry/Outline")
		(27 "Margin" user)
		(31 "F.CrtYd" user "Package Geometry/Place Bound Top")
		(29 "B.CrtYd" user "Package Geometry/Place Bound Bottom")
		(35 "F.Fab" user "Ref Des/Assembly Top")
		(33 "B.Fab" user "Ref Des/Assembly Bottom")
	)
	(footprint ""
		(layer "F.Cu")
		(at 336.899758 -48.450246)
		(property "Reference" "U4"
			(at -13.479018 -11.486896 0)
			(unlocked yes)
			(layer "F.SilkS")
			(effects
				(font
					(size 0.7874 0.5842)
					(thickness 0.1524)
				)
				(justify left)
			)
		)
		(property "Value" ""
			(at 0 0 0)
			(layer "F.Fab")
			(effects
				(font
					(size 1.27 1.27)
				)
			)
		)
		(duplicate_pad_numbers_are_jumpers no)
		(pad "BA13" smd circle
			(at -4.477512 7.9883 180)
			(size 0.381 0.381)
			(layers "F.Cu" "F.Mask" "F.Paste")
			(net "SPI_PCH_IO0")
		)
		(pad "BA16" smd circle
			(at -2.849118 7.9883 180)
			(size 0.381 0.381)
			(layers "F.Cu" "F.Mask" "F.Paste")
			(net "SPI_PCH_IO3")
		)
		(pad "BA20" smd circle
			(at -1.220978 7.9883 180)
			(size 0.381 0.381)
			(layers "F.Cu" "F.Mask" "F.Paste")
			(net "FM_PS_PWROK_DLY_R_SEL")
		)
		(pad "BA23" smd circle
			(at 0.406908 7.9883 180)
			(size 0.381 0.381)
			(layers "F.Cu" "F.Mask" "F.Paste")
			(net "TP_PCH_GPP_E_1")
		)
		(pad "BA26" smd circle
			(at 2.035302 7.9883 180)
			(size 0.381 0.381)
			(layers "F.Cu" "F.Mask" "F.Paste")
			(net "TP_PCH_GPP_E_0")
		)
		(pad "BA29" smd circle
			(at 3.663188 7.9883 180)
			(size 0.381 0.381)
			(layers "F.Cu" "F.Mask" "F.Paste")
			(net "PD_PCH_GPP_E_9")
		)
		(pad "BA32" smd circle
			(at 5.291582 7.9883 180)
			(size 0.381 0.381)
			(layers "F.Cu" "F.Mask" "F.Paste")
			(net "PD_PCH_GPP_E_13")
		)
		(pad "BA36" smd circle
			(at 6.919722 7.9883 180)
			(size 0.381 0.381)
			(layers "F.Cu" "F.Mask" "F.Paste")
			(net "FM_DEBUG_PORT_PRSNT_R_N")
		)
		(pad "BA40" smd circle
			(at 9.069832 8.003794 180)
			(size 0.3048 0.3048)
			(layers "F.Cu" "F.Mask" "F.Paste")
			(net "TP_USB2_12_DP")
		)
		(pad "BA42" smd circle
			(at 9.899904 8.003794 180)
			(size 0.3048 0.3048)
			(layers "F.Cu" "F.Mask" "F.Paste")
			(net "TP_USB2_12_DN")
		)
		(pad "BB1" smd circle
			(at -10.31494 8.504174 180)
			(size 0.3048 0.3048)
			(layers "F.Cu" "F.Mask" "F.Paste")
			(net "GND")
		)
		(pad "BB3" smd circle
			(at -9.484868 8.504174 180)
			(size 0.3048 0.3048)
			(layers "F.Cu" "F.Mask" "F.Paste")
			(net "SMB_SML0B_3V3AUX_SCL")
		)
		(pad "BB5" smd circle
			(at -8.654796 8.504174 180)
			(size 0.3048 0.3048)
			(layers "F.Cu" "F.Mask" "F.Paste")
			(net "GND")
		)
		(pad "BB8" smd circle
			(at -6.919722 8.4582 180)
			(size 0.381 0.381)
			(layers "F.Cu" "F.Mask" "F.Paste")
			(net "FM_ESPI_CS_SWIZZLE")
		)
		(pad "BB11" smd circle
			(at -5.291582 8.4582 180)
			(size 0.381 0.381)
			(layers "F.Cu" "F.Mask" "F.Paste")
			(net "SPI_PCH_TPM_CS_N")
		)
		(pad "BB15" smd circle
			(at -3.663188 8.4582 180)
			(size 0.381 0.381)
			(layers "F.Cu" "F.Mask" "F.Paste")
			(net "SPI_PCH_CLK")
		)
		(pad "BB18" smd circle
			(at -2.035302 8.4582 180)
			(size 0.381 0.381)
			(layers "F.Cu" "F.Mask" "F.Paste")
			(net "FM_XTAL_INPUT_FREQUENCY_0_MGPIO")
		)
		(pad "BB21" smd circle
			(at -0.406908 8.4582 180)
			(size 0.381 0.381)
			(layers "F.Cu" "F.Mask" "F.Paste")
			(net "PD_PCH_GPP_E_3")
		)
		(pad "BB24" smd circle
			(at 1.220978 8.4582 180)
			(size 0.381 0.381)
			(layers "F.Cu" "F.Mask" "F.Paste")
			(net "FM_M2_E1S_E6_PEDET")
		)
		(pad "BB28" smd circle
			(at 2.849118 8.4582 180)
			(size 0.381 0.381)
			(layers "F.Cu" "F.Mask" "F.Paste")
			(net "PD_PCH_GPP_E_12")
		)
		(pad "BB31" smd circle
			(at 4.477512 8.4582 180)
			(size 0.381 0.381)
			(layers "F.Cu" "F.Mask" "F.Paste")
			(net "FM_TPM_PRSNT_N")
		)
		(pad "BB34" smd circle
			(at 6.105398 8.4582 180)
			(size 0.381 0.381)
			(layers "F.Cu" "F.Mask" "F.Paste")
			(net "PD_PCH_GPP_E_14")
		)
		(pad "BB37" smd circle
			(at 7.733792 8.4582 180)
			(size 0.381 0.381)
			(layers "F.Cu" "F.Mask" "F.Paste")
			(net "H_DBP_PRDY_N_PCH")
		)
		(pad "BB39" smd circle
			(at 8.654796 8.504174 180)
			(size 0.3048 0.3048)
			(layers "F.Cu" "F.Mask" "F.Paste")
			(net "GND")
		)
		(pad "BB41" smd circle
			(at 9.484868 8.504174 180)
			(size 0.3048 0.3048)
			(layers "F.Cu" "F.Mask" "F.Paste")
			(net "PD_PCH_USB2_COMP")
		)
		(pad "BB43" smd circle
			(at 10.31494 8.504174 180)
			(size 0.4064 0.4064)
			(layers "F.Cu" "F.Mask" "F.Paste")
			(net "TP_PCH_RSVD<7>")
		)
		(pad "BC2" smd circle
			(at -9.899904 9.0043 180)
			(size 0.3048 0.3048)
			(layers "F.Cu" "F.Mask" "F.Paste")
			(net "GND")
		)
		(pad "BC4" smd circle
			(at -9.069832 9.0043 180)
			(size 0.3048 0.3048)
			(layers "F.Cu" "F.Mask" "F.Paste")
			(net "SMB_SML0_3V3AUX_PCH_SCL")
		)
		(pad "BC6" smd circle
			(at -8.003794 9.154922 180)
			(size 0.3048 0.3048)
			(layers "F.Cu" "F.Mask" "F.Paste")
			(net "GND")
		)
		(pad "BC8" smd circle
			(at -7.003288 9.154922 180)
			(size 0.3048 0.3048)
			(layers "F.Cu" "F.Mask" "F.Paste")
			(net "GND")
		)
		(pad "BC10" smd circle
			(at -6.002782 9.154922 180)
			(size 0.3048 0.3048)
			(layers "F.Cu" "F.Mask" "F.Paste")
			(net "GND")
		)
		(pad "BC12" smd circle
			(at -5.002276 9.154922 180)
			(size 0.3048 0.3048)
			(layers "F.Cu" "F.Mask" "F.Paste")
			(net "GND")
		)
		(pad "BC14" smd circle
			(at -4.002024 9.154922 180)
			(size 0.3048 0.3048)
			(layers "F.Cu" "F.Mask" "F.Paste")
			(net "GND")
		)
		(pad "BC16" smd circle
			(at -3.001518 9.154922 180)
			(size 0.3048 0.3048)
			(layers "F.Cu" "F.Mask" "F.Paste")
			(net "GND")
		)
		(pad "BC18" smd circle
			(at -2.001012 9.154922 180)
			(size 0.3048 0.3048)
			(layers "F.Cu" "F.Mask" "F.Paste")
			(net "GND")
		)
		(pad "BC20" smd circle
			(at -1.000506 9.154922 180)
			(size 0.3048 0.3048)
			(layers "F.Cu" "F.Mask" "F.Paste")
			(net "GND")
		)
		(pad "BC22" smd circle
			(at 0 9.154922 180)
			(size 0.3048 0.3048)
			(layers "F.Cu" "F.Mask" "F.Paste")
			(net "GND")
		)
		(pad "BC24" smd circle
			(at 1.000506 9.154922 180)
			(size 0.3048 0.3048)
			(layers "F.Cu" "F.Mask" "F.Paste")
			(net "GND")
		)
		(pad "BC26" smd circle
			(at 2.001012 9.154922 180)
			(size 0.3048 0.3048)
			(layers "F.Cu" "F.Mask" "F.Paste")
			(net "GND")
		)
		(pad "BC28" smd circle
			(at 3.001518 9.154922 180)
			(size 0.3048 0.3048)
			(layers "F.Cu" "F.Mask" "F.Paste")
			(net "GND")
		)
		(pad "BC30" smd circle
			(at 4.002024 9.154922 180)
			(size 0.3048 0.3048)
			(layers "F.Cu" "F.Mask" "F.Paste")
			(net "GND")
		)
		(pad "BC32" smd circle
			(at 5.002276 9.154922 180)
			(size 0.3048 0.3048)
			(layers "F.Cu" "F.Mask" "F.Paste")
			(net "GND")
		)
		(pad "BC34" smd circle
			(at 6.002782 9.154922 180)
			(size 0.3048 0.3048)
			(layers "F.Cu" "F.Mask" "F.Paste")
			(net "GND")
		)
		(pad "BC36" smd circle
			(at 7.003288 9.154922 180)
			(size 0.3048 0.3048)
			(layers "F.Cu" "F.Mask" "F.Paste")
			(net "GND")
		)
		(pad "BC38" smd circle
			(at 8.003794 9.154922 180)
			(size 0.3048 0.3048)
			(layers "F.Cu" "F.Mask" "F.Paste")
			(net "GND")
		)
		(pad "BC40" smd circle
			(at 9.069832 9.0043 180)
			(size 0.3048 0.3048)
			(layers "F.Cu" "F.Mask" "F.Paste")
			(net "NC_PCH_RSVD<14>")
		)
		(pad "BC42" smd circle
			(at 9.899904 9.0043 180)
			(size 0.3048 0.3048)
			(layers "F.Cu" "F.Mask" "F.Paste")
			(net "GND")
		)
		(pad "BD1" smd circle
			(at -10.31494 9.50468 180)
			(size 0.4064 0.4064)
			(layers "F.Cu" "F.Mask" "F.Paste")
			(net "GND")
		)
		(pad "BD3" smd circle
			(at -9.484868 9.50468 180)
			(size 0.3048 0.3048)
			(layers "F.Cu" "F.Mask" "F.Paste")
			(net "GND")
		)
		(pad "BD5" smd circle
			(at -8.504174 9.569958 180)
			(size 0.3048 0.3048)
			(layers "F.Cu" "F.Mask" "F.Paste")
			(net "GND")
		)
		(pad "BD7" smd circle
			(at -7.503668 9.569958 180)
			(size 0.3048 0.3048)
			(layers "F.Cu" "F.Mask" "F.Paste")
			(net "RST_RTCRST_N")
		)
		(pad "BD9" smd circle
			(at -6.503162 9.569958 180)
			(size 0.3048 0.3048)
			(layers "F.Cu" "F.Mask" "F.Paste")
			(net "RST_RSMRST_PCH_N")
		)
		(pad "BD11" smd circle
			(at -5.502656 9.569958 180)
			(size 0.3048 0.3048)
			(layers "F.Cu" "F.Mask" "F.Paste")
			(net "FM_PCH_SATA_RAID_KEY")
		)
		(pad "BD13" smd circle
			(at -4.50215 9.569958 180)
			(size 0.3048 0.3048)
			(layers "F.Cu" "F.Mask" "F.Paste")
			(net "CLK_24M_66M_LPC0_ESPI")
		)
		(pad "BD15" smd circle
			(at -3.501644 9.569958 180)
			(size 0.3048 0.3048)
			(layers "F.Cu" "F.Mask" "F.Paste")
			(net "ESPI_ALERT1_N_LPC_RCIN_N")
		)
		(pad "BD17" smd circle
			(at -2.501138 9.569958 180)
			(size 0.3048 0.3048)
			(layers "F.Cu" "F.Mask" "F.Paste")
			(net "PD_PCH_GPPC_A_10")
		)
		(pad "BD19" smd circle
			(at -1.500632 9.569958 180)
			(size 0.3048 0.3048)
			(layers "F.Cu" "F.Mask" "F.Paste")
			(net "ESPI_LAD0_DATA_IO3")
		)
		(pad "BD21" smd circle
			(at -0.500126 9.569958 180)
			(size 0.3048 0.3048)
			(layers "F.Cu" "F.Mask" "F.Paste")
			(net "GND")
		)
		(pad "BD23" smd circle
			(at 0.500126 9.569958 180)
			(size 0.3048 0.3048)
			(layers "F.Cu" "F.Mask" "F.Paste")
			(net "JTAG_TRC_PCH_PTI1_CLK")
		)
		(pad "BD25" smd circle
			(at 1.500632 9.569958 180)
			(size 0.3048 0.3048)
			(layers "F.Cu" "F.Mask" "F.Paste")
			(net "JTAG_TRC_PCH_PTI<11>")
		)
		(pad "BD27" smd circle
			(at 2.501138 9.569958 180)
			(size 0.3048 0.3048)
			(layers "F.Cu" "F.Mask" "F.Paste")
			(net "JTAG_TRC_PCH_PTI<8>")
		)
		(pad "BD29" smd circle
			(at 3.501644 9.569958 180)
			(size 0.3048 0.3048)
			(layers "F.Cu" "F.Mask" "F.Paste")
			(net "JTAG_TRC_PCH_PTI<5>")
		)
		(pad "BD31" smd circle
			(at 4.50215 9.569958 180)
			(size 0.3048 0.3048)
			(layers "F.Cu" "F.Mask" "F.Paste")
			(net "JTAG_TRC_PCH_PTI<2>")
		)
		(pad "BD33" smd circle
			(at 5.502656 9.569958 180)
			(size 0.3048 0.3048)
			(layers "F.Cu" "F.Mask" "F.Paste")
			(net "JTAG_TRC_PCH_PTI0_CLK")
		)
		(pad "BD35" smd circle
			(at 6.503162 9.569958 180)
			(size 0.3048 0.3048)
			(layers "F.Cu" "F.Mask" "F.Paste")
			(net "JTAG_DBP_CPU_GTL_TCK")
		)
		(pad "BD37" smd circle
			(at 7.503668 9.569958 180)
			(size 0.3048 0.3048)
			(layers "F.Cu" "F.Mask" "F.Paste")
			(net "JTAG_DBP_TMS_PCH")
		)
		(pad "BD39" smd circle
			(at 8.504174 9.569958 180)
			(size 0.3048 0.3048)
			(layers "F.Cu" "F.Mask" "F.Paste")
			(net "GND")
		)
		(pad "BD41" smd circle
			(at 9.484868 9.50468 180)
			(size 0.3048 0.3048)
			(layers "F.Cu" "F.Mask" "F.Paste")
			(net "GND")
		)
		(pad "BD43" smd circle
			(at 10.31494 9.50468 180)
			(size 0.4064 0.4064)
			(layers "F.Cu" "F.Mask" "F.Paste")
			(net "GND")
		)
		(pad "BE1" smd circle
			(at -10.31494 10.159746 180)
			(size 0.4064 0.4064)
			(layers "F.Cu" "F.Mask" "F.Paste")
			(net "GND")
		)
		(pad "BE3" smd circle
			(at -9.65962 10.159746 180)
			(size 0.3048 0.3048)
			(layers "F.Cu" "F.Mask" "F.Paste")
			(net "GND")
		)
		(pad "BE4" smd circle
			(at -9.0043 9.984994 180)
			(size 0.3048 0.3048)
			(layers "F.Cu" "F.Mask" "F.Paste")
			(net "PWRGD_PCH_PWROK")
		)
		(pad "BE6" smd circle
			(at -8.003794 9.984994 180)
			(size 0.3048 0.3048)
			(layers "F.Cu" "F.Mask" "F.Paste")
			(net "XTAL_PCH_RTC1")
		)
		(pad "BE8" smd circle
			(at -7.003288 9.984994 180)
			(size 0.3048 0.3048)
			(layers "F.Cu" "F.Mask" "F.Paste")
			(net "PWRGD_DSW_PWROK")
		)
		(pad "BE10" smd circle
			(at -6.002782 9.984994 180)
			(size 0.3048 0.3048)
			(layers "F.Cu" "F.Mask" "F.Paste")
			(net "GND")
		)
		(pad "BE12" smd circle
			(at -5.002276 9.984994 180)
			(size 0.3048 0.3048)
			(layers "F.Cu" "F.Mask" "F.Paste")
			(net "PD_PCH_GPPC_A_14")
		)
		(pad "BE14" smd circle
			(at -4.002024 9.984994 180)
			(size 0.3048 0.3048)
			(layers "F.Cu" "F.Mask" "F.Paste")
			(net "PD_PCH_GPPC_A_15")
		)
		(pad "BE16" smd circle
			(at -3.001518 9.984994 180)
			(size 0.3048 0.3048)
			(layers "F.Cu" "F.Mask" "F.Paste")
			(net "IRQ_LPC_SERIRQ_ESPI_CS1_N")
		)
		(pad "BE18" smd circle
			(at -2.001012 9.984994 180)
			(size 0.3048 0.3048)
			(layers "F.Cu" "F.Mask" "F.Paste")
			(net "ESPI_LAD0_DATA_IO2")
		)
		(pad "BE20" smd circle
			(at -1.000506 9.984994 180)
			(size 0.3048 0.3048)
			(layers "F.Cu" "F.Mask" "F.Paste")
			(net "ESPI_LFRAME_N_BMC_CS0_N")
		)
		(pad "BE22" smd circle
			(at 0 9.984994 180)
			(size 0.3048 0.3048)
			(layers "F.Cu" "F.Mask" "F.Paste")
			(net "JTAG_TRC_PCH_PTI<15>")
		)
		(pad "BE24" smd circle
			(at 1.000506 9.984994 180)
			(size 0.3048 0.3048)
			(layers "F.Cu" "F.Mask" "F.Paste")
			(net "JTAG_TRC_PCH_PTI<13>")
		)
		(pad "BE26" smd circle
			(at 2.001012 9.984994 180)
			(size 0.3048 0.3048)
			(layers "F.Cu" "F.Mask" "F.Paste")
			(net "JTAG_TRC_PCH_PTI<9>")
		)
		(pad "BE28" smd circle
			(at 3.001518 9.984994 180)
			(size 0.3048 0.3048)
			(layers "F.Cu" "F.Mask" "F.Paste")
			(net "JTAG_TRC_PCH_PTI<6>")
		)
		(pad "BE30" smd circle
			(at 4.002024 9.984994 180)
			(size 0.3048 0.3048)
			(layers "F.Cu" "F.Mask" "F.Paste")
			(net "JTAG_TRC_PCH_PTI<3>")
		)
		(pad "BE32" smd circle
			(at 5.002276 9.984994 180)
			(size 0.3048 0.3048)
			(layers "F.Cu" "F.Mask" "F.Paste")
			(net "JTAG_TRC_PCH_PTI<0>")
		)
		(pad "BE34" smd circle
			(at 6.002782 9.984994 180)
			(size 0.3048 0.3048)
			(layers "F.Cu" "F.Mask" "F.Paste")
			(net "GND")
		)
		(pad "BE36" smd circle
			(at 7.003288 9.984994 180)
			(size 0.3048 0.3048)
			(layers "F.Cu" "F.Mask" "F.Paste")
			(net "JTAG_DBP_TDO_PCH")
		)
		(pad "BE38" smd circle
			(at 8.003794 9.984994 180)
			(size 0.3048 0.3048)
			(layers "F.Cu" "F.Mask" "F.Paste")
			(net "JTAG_DBP_TDI_PCH")
		)
		(pad "BE40" smd circle
			(at 9.0043 9.984994 180)
			(size 0.3048 0.3048)
			(layers "F.Cu" "F.Mask" "F.Paste")
			(net "JTAG_DBP_PMODE")
		)
		(pad "BE41" smd circle
			(at 9.65962 10.159746 180)
			(size 0.3048 0.3048)
			(layers "F.Cu" "F.Mask" "F.Paste")
			(net "GND")
		)
		(pad "BE43" smd circle
			(at 10.31494 10.159746 180)
			(size 0.4064 0.4064)
			(layers "F.Cu" "F.Mask" "F.Paste")
			(net "GND")
		)
		(pad "BF5" smd circle
			(at -8.504174 10.40003 180)
			(size 0.3048 0.3048)
			(layers "F.Cu" "F.Mask" "F.Paste")
			(net "RTC_EXT_CAP")
		)
		(pad "BF7" smd circle
			(at -7.503668 10.40003 180)
			(size 0.3048 0.3048)
			(layers "F.Cu" "F.Mask" "F.Paste")
			(net "XTAL_PCH_RTC2")
		)
		(pad "BF9" smd circle
			(at -6.503162 10.40003 180)
			(size 0.3048 0.3048)
			(layers "F.Cu" "F.Mask" "F.Paste")
			(net "RST_SRTCRST_N")
		)
		(pad "BF11" smd circle
			(at -5.502656 10.40003 180)
			(size 0.3048 0.3048)
			(layers "F.Cu" "F.Mask" "F.Paste")
			(net "PD_PCH_GPPC_A_18")
		)
		(pad "BF13" smd circle
			(at -4.50215 10.40003 180)
			(size 0.3048 0.3048)
			(layers "F.Cu" "F.Mask" "F.Paste")
			(net "IRQ_BMC_PCH_NMI")
		)
		(pad "BF15" smd circle
			(at -3.501644 10.40003 180)
			(size 0.3048 0.3048)
			(layers "F.Cu" "F.Mask" "F.Paste")
			(net "FM_BMC_READY_R_N")
		)
		(pad "BF17" smd circle
			(at -2.501138 10.40003 180)
			(size 0.3048 0.3048)
			(layers "F.Cu" "F.Mask" "F.Paste")
			(net "RST_ESPI_RESET_N")
		)
		(pad "BF19" smd circle
			(at -1.500632 10.40003 180)
			(size 0.3048 0.3048)
			(layers "F.Cu" "F.Mask" "F.Paste")
			(net "ESPI_LAD0_DATA_IO1")
		)
		(pad "BF21" smd circle
			(at -0.500126 10.40003 180)
			(size 0.3048 0.3048)
			(layers "F.Cu" "F.Mask" "F.Paste")
			(net "GND")
		)
		(pad "BF23" smd circle
			(at 0.500126 10.40003 180)
			(size 0.3048 0.3048)
			(layers "F.Cu" "F.Mask" "F.Paste")
			(net "JTAG_TRC_PCH_PTI<14>")
		)
		(pad "BF25" smd circle
			(at 1.500632 10.40003 180)
			(size 0.3048 0.3048)
			(layers "F.Cu" "F.Mask" "F.Paste")
			(net "JTAG_TRC_PCH_PTI<12>")
		)
		(pad "BF27" smd circle
			(at 2.501138 10.40003 180)
			(size 0.3048 0.3048)
			(layers "F.Cu" "F.Mask" "F.Paste")
			(net "JTAG_TRC_PCH_PTI<10>")
		)
		(pad "BF29" smd circle
			(at 3.501644 10.40003 180)
			(size 0.3048 0.3048)
			(layers "F.Cu" "F.Mask" "F.Paste")
			(net "JTAG_TRC_PCH_PTI<7>")
		)
		(pad "BF31" smd circle
			(at 4.50215 10.40003 180)
			(size 0.3048 0.3048)
			(layers "F.Cu" "F.Mask" "F.Paste")
			(net "JTAG_TRC_PCH_PTI<4>")
		)
		(pad "BF33" smd circle
			(at 5.502656 10.40003 180)
			(size 0.3048 0.3048)
			(layers "F.Cu" "F.Mask" "F.Paste")
			(net "JTAG_TRC_PCH_PTI<1>")
		)
		(pad "BF35" smd circle
			(at 6.503162 10.40003 180)
			(size 0.3048 0.3048)
			(layers "F.Cu" "F.Mask" "F.Paste")
			(net "JTAG_DBP_TCK_PCH")
		)
		(pad "BF37" smd circle
			(at 7.503668 10.40003 180)
			(size 0.3048 0.3048)
			(layers "F.Cu" "F.Mask" "F.Paste")
			(net "H_DBP_PREQ_N_PCH")
		)
		(pad "BF39" smd circle
			(at 8.504174 10.40003 180)
			(size 0.3048 0.3048)
			(layers "F.Cu" "F.Mask" "F.Paste")
			(net "NC_PCH_RSVD<5>")
		)
	)
)
